(kicad_pcb
	(version 20260206)
	(generator "pcbnew")
	(generator_version "10.0")
	(general
		(thickness 1.6)
		(legacy_teardrops no)
	)
	(paper "A4")
	(title_block
		(title "01162023_DA0F0TEBIF0_F0T_Expander_BD_F_brd_V02_OCP.brd")
		(comment 1 "Grand Teton / footprints 1460-1465 of 9728")
	)
	(layers
		(0 "F.Cu" signal "TOP")
		(4 "In1.Cu" signal "GND")
		(6 "In2.Cu" signal "VCC")
		(8 "In3.Cu" signal "VCC1")
		(10 "In4.Cu" signal "GND1")
		(12 "In5.Cu" signal "IN1")
		(14 "In6.Cu" signal "GND2")
		(16 "In7.Cu" signal "IN2")
		(18 "In8.Cu" signal "GND3")
		(20 "In9.Cu" signal "IN3")
		(22 "In10.Cu" signal "GND4")
		(24 "In11.Cu" signal "IN4")
		(26 "In12.Cu" signal "GND5")
		(28 "In13.Cu" signal "IN5")
		(30 "In14.Cu" signal "GND6")
		(32 "In15.Cu" signal "IN6")
		(34 "In16.Cu" signal "GND7")
		(2 "B.Cu" signal "BOTTOM")
		(9 "F.Adhes" user "F.Adhesive")
		(11 "B.Adhes" user "B.Adhesive")
		(13 "F.Paste" user "Package Geometry/Pastemask Top")
		(15 "B.Paste" user "Package Geometry/Pastemask Bottom")
		(5 "F.SilkS" user "Ref Des/Silkscreen Top")
		(7 "B.SilkS" user "Ref Des/Silkscreen Bottom")
		(1 "F.Mask" user "Board Geometry/Soldermask Top")
		(3 "B.Mask" user "Board Geometry/Soldermask Bottom")
		(17 "Dwgs.User" user "User.Drawings")
		(19 "Cmts.User" user "User.Comments")
		(21 "Eco1.User" user "User.Eco1")
		(23 "Eco2.User" user "User.Eco2")
		(25 "Edge.Cuts" user "Board Geometry/Outline")
		(27 "Margin" user)
		(31 "F.CrtYd" user "Package Geometry/Place Bound Top")
		(29 "B.CrtYd" user "Package Geometry/Place Bound Bottom")
		(35 "F.Fab" user "Ref Des/Assembly Top")
		(33 "B.Fab" user "Ref Des/Assembly Bottom")
	)
	(footprint ""
		(layer "F.Cu")
		(at 235.623608 -142.640812 180)
		(property "Reference" "R4208"
			(at 0 0 180)
			(layer "F.SilkS")
			(hide yes)
			(effects
				(font
					(size 1.27 1.27)
				)
			)
		)
		(property "Value" ""
			(at 0 0 180)
			(layer "F.Fab")
			(effects
				(font
					(size 1.27 1.27)
				)
			)
		)
		(duplicate_pad_numbers_are_jumpers no)
		(fp_line
			(start 0.7874 0.4064)
			(end -0.7874 0.4064)
			(stroke
				(width 0.1524)
				(type default)
			)
			(layer "F.SilkS")
		)
		(fp_line
			(start 0.7874 -0.4064)
			(end 0.7874 0.4064)
			(stroke
				(width 0.1524)
				(type default)
			)
			(layer "F.SilkS")
		)
		(fp_line
			(start -0.7874 0.4064)
			(end -0.7874 -0.4064)
			(stroke
				(width 0.1524)
				(type default)
			)
			(layer "F.SilkS")
		)
		(fp_line
			(start -0.7874 -0.4064)
			(end 0.7874 -0.4064)
			(stroke
				(width 0.1524)
				(type default)
			)
			(layer "F.SilkS")
		)
		(fp_line
			(start 0.67945 0.3048)
			(end 0.120396 0.3048)
			(stroke
				(width 0.1)
				(type default)
			)
			(layer "F.Fab")
		)
		(fp_line
			(start 0.67945 -0.3048)
			(end 0.67945 0.3048)
			(stroke
				(width 0.1)
				(type default)
			)
			(layer "F.Fab")
		)
		(fp_line
			(start 0.12065 -0.2794)
			(end 0.12065 -0.3048)
			(stroke
				(width 0.1)
				(type default)
			)
			(layer "F.Fab")
		)
		(fp_line
			(start 0.12065 -0.3048)
			(end 0.67945 -0.3048)
			(stroke
				(width 0.1)
				(type default)
			)
			(layer "F.Fab")
		)
		(fp_line
			(start 0.120396 0.3048)
			(end 0.120396 0.2794)
			(stroke
				(width 0.1)
				(type default)
			)
			(layer "F.Fab")
		)
		(fp_line
			(start 0.120396 0.2794)
			(end -0.12065 0.2794)
			(stroke
				(width 0.1)
				(type default)
			)
			(layer "F.Fab")
		)
		(fp_line
			(start -0.12065 0.3048)
			(end -0.67945 0.3048)
			(stroke
				(width 0.1)
				(type default)
			)
			(layer "F.Fab")
		)
		(fp_line
			(start -0.12065 0.2794)
			(end -0.12065 0.3048)
			(stroke
				(width 0.1)
				(type default)
			)
			(layer "F.Fab")
		)
		(fp_line
			(start -0.12065 -0.2794)
			(end 0.12065 -0.2794)
			(stroke
				(width 0.1)
				(type default)
			)
			(layer "F.Fab")
		)
		(fp_line
			(start -0.12065 -0.305054)
			(end -0.12065 -0.2794)
			(stroke
				(width 0.1)
				(type default)
			)
			(layer "F.Fab")
		)
		(fp_line
			(start -0.67945 0.3048)
			(end -0.67945 -0.305054)
			(stroke
				(width 0.1)
				(type default)
			)
			(layer "F.Fab")
		)
		(fp_line
			(start -0.67945 -0.305054)
			(end -0.12065 -0.305054)
			(stroke
				(width 0.1)
				(type default)
			)
			(layer "F.Fab")
		)
		(pad "1" smd circle
			(at -0.40005 0 180)
			(size 0 0)
			(layers "F.Cu" "F.Mask" "F.Paste")
			(net "GND")
		)
		(pad "2" smd circle
			(at 0.40005 0 180)
			(size 0 0)
			(layers "F.Cu" "F.Mask" "F.Paste")
			(net "CK440_PEX_SS_EN")
		)
	)
	(footprint ""
		(layer "F.Cu")
		(at 95.105728 -239.728248)
		(property "Reference" "R819"
			(at 0 0 0)
			(layer "F.SilkS")
			(hide yes)
			(effects
				(font
					(size 1.27 1.27)
				)
			)
		)
		(property "Value" ""
			(at 0 0 0)
			(layer "F.Fab")
			(effects
				(font
					(size 1.27 1.27)
				)
			)
		)
		(duplicate_pad_numbers_are_jumpers no)
		(fp_line
			(start -0.7874 -0.4064)
			(end 0.7874 -0.4064)
			(stroke
				(width 0.1524)
				(type default)
			)
			(layer "F.SilkS")
		)
		(fp_line
			(start -0.7874 0.4064)
			(end -0.7874 -0.4064)
			(stroke
				(width 0.1524)
				(type default)
			)
			(layer "F.SilkS")
		)
		(fp_line
			(start 0.7874 -0.4064)
			(end 0.7874 0.4064)
			(stroke
				(width 0.1524)
				(type default)
			)
			(layer "F.SilkS")
		)
		(fp_line
			(start 0.7874 0.4064)
			(end -0.7874 0.4064)
			(stroke
				(width 0.1524)
				(type default)
			)
			(layer "F.SilkS")
		)
		(fp_line
			(start -0.67945 -0.305054)
			(end -0.12065 -0.305054)
			(stroke
				(width 0.1)
				(type default)
			)
			(layer "F.Fab")
		)
		(fp_line
			(start -0.67945 0.3048)
			(end -0.67945 -0.305054)
			(stroke
				(width 0.1)
				(type default)
			)
			(layer "F.Fab")
		)
		(fp_line
			(start -0.12065 -0.305054)
			(end -0.12065 -0.2794)
			(stroke
				(width 0.1)
				(type default)
			)
			(layer "F.Fab")
		)
		(fp_line
			(start -0.12065 -0.2794)
			(end 0.12065 -0.2794)
			(stroke
				(width 0.1)
				(type default)
			)
			(layer "F.Fab")
		)
		(fp_line
			(start -0.12065 0.2794)
			(end -0.12065 0.3048)
			(stroke
				(width 0.1)
				(type default)
			)
			(layer "F.Fab")
		)
		(fp_line
			(start -0.12065 0.3048)
			(end -0.67945 0.3048)
			(stroke
				(width 0.1)
				(type default)
			)
			(layer "F.Fab")
		)
		(fp_line
			(start 0.120396 0.2794)
			(end -0.12065 0.2794)
			(stroke
				(width 0.1)
				(type default)
			)
			(layer "F.Fab")
		)
		(fp_line
			(start 0.120396 0.3048)
			(end 0.120396 0.2794)
			(stroke
				(width 0.1)
				(type default)
			)
			(layer "F.Fab")
		)
		(fp_line
			(start 0.12065 -0.3048)
			(end 0.67945 -0.3048)
			(stroke
				(width 0.1)
				(type default)
			)
			(layer "F.Fab")
		)
		(fp_line
			(start 0.12065 -0.2794)
			(end 0.12065 -0.3048)
			(stroke
				(width 0.1)
				(type default)
			)
			(layer "F.Fab")
		)
		(fp_line
			(start 0.67945 -0.3048)
			(end 0.67945 0.3048)
			(stroke
				(width 0.1)
				(type default)
			)
			(layer "F.Fab")
		)
		(fp_line
			(start 0.67945 0.3048)
			(end 0.120396 0.3048)
			(stroke
				(width 0.1)
				(type default)
			)
			(layer "F.Fab")
		)
		(pad "1" smd circle
			(at -0.40005 0)
			(size 0 0)
			(layers "F.Cu" "F.Mask" "F.Paste")
			(net "SMB_BIC_I2C6_MUX_PEX_ADC_R_SCL")
		)
		(pad "2" smd circle
			(at 0.40005 0)
			(size 0 0)
			(layers "F.Cu" "F.Mask" "F.Paste")
			(net "SMB_PEX_P1V8_ADC_SCL")
		)
	)
	(footprint ""
		(layer "F.Cu")
		(at 28.875228 -64.102234 180)
		(property "Reference" "PR6908"
			(at 0 0 180)
			(layer "F.SilkS")
			(hide yes)
			(effects
				(font
					(size 1.27 1.27)
				)
			)
		)
		(property "Value" ""
			(at 0 0 180)
			(layer "F.Fab")
			(effects
				(font
					(size 1.27 1.27)
				)
			)
		)
		(duplicate_pad_numbers_are_jumpers no)
		(fp_line
			(start 0.7874 0.4064)
			(end -0.7874 0.4064)
			(stroke
				(width 0.1524)
				(type default)
			)
			(layer "F.SilkS")
		)
		(fp_line
			(start 0.7874 -0.4064)
			(end 0.7874 0.4064)
			(stroke
				(width 0.1524)
				(type default)
			)
			(layer "F.SilkS")
		)
		(fp_line
			(start -0.7874 0.4064)
			(end -0.7874 -0.4064)
			(stroke
				(width 0.1524)
				(type default)
			)
			(layer "F.SilkS")
		)
		(fp_line
			(start -0.7874 -0.4064)
			(end 0.7874 -0.4064)
			(stroke
				(width 0.1524)
				(type default)
			)
			(layer "F.SilkS")
		)
		(fp_line
			(start 0.67945 0.3048)
			(end 0.120396 0.3048)
			(stroke
				(width 0.1)
				(type default)
			)
			(layer "F.Fab")
		)
		(fp_line
			(start 0.67945 -0.3048)
			(end 0.67945 0.3048)
			(stroke
				(width 0.1)
				(type default)
			)
			(layer "F.Fab")
		)
		(fp_line
			(start 0.12065 -0.2794)
			(end 0.12065 -0.3048)
			(stroke
				(width 0.1)
				(type default)
			)
			(layer "F.Fab")
		)
		(fp_line
			(start 0.12065 -0.3048)
			(end 0.67945 -0.3048)
			(stroke
				(width 0.1)
				(type default)
			)
			(layer "F.Fab")
		)
		(fp_line
			(start 0.120396 0.3048)
			(end 0.120396 0.2794)
			(stroke
				(width 0.1)
				(type default)
			)
			(layer "F.Fab")
		)
		(fp_line
			(start 0.120396 0.2794)
			(end -0.12065 0.2794)
			(stroke
				(width 0.1)
				(type default)
			)
			(layer "F.Fab")
		)
		(fp_line
			(start -0.12065 0.3048)
			(end -0.67945 0.3048)
			(stroke
				(width 0.1)
				(type default)
			)
			(layer "F.Fab")
		)
		(fp_line
			(start -0.12065 0.2794)
			(end -0.12065 0.3048)
			(stroke
				(width 0.1)
				(type default)
			)
			(layer "F.Fab")
		)
		(fp_line
			(start -0.12065 -0.2794)
			(end 0.12065 -0.2794)
			(stroke
				(width 0.1)
				(type default)
			)
			(layer "F.Fab")
		)
		(fp_line
			(start -0.12065 -0.305054)
			(end -0.12065 -0.2794)
			(stroke
				(width 0.1)
				(type default)
			)
			(layer "F.Fab")
		)
		(fp_line
			(start -0.67945 0.3048)
			(end -0.67945 -0.305054)
			(stroke
				(width 0.1)
				(type default)
			)
			(layer "F.Fab")
		)
		(fp_line
			(start -0.67945 -0.305054)
			(end -0.12065 -0.305054)
			(stroke
				(width 0.1)
				(type default)
			)
			(layer "F.Fab")
		)
		(pad "1" smd circle
			(at -0.40005 0 180)
			(size 0 0)
			(layers "F.Cu" "F.Mask" "F.Paste")
			(net "P12V_SSD1_PG_G1")
		)
		(pad "2" smd circle
			(at 0.40005 0 180)
			(size 0 0)
			(layers "F.Cu" "F.Mask" "F.Paste")
			(net "GND")
		)
	)
	(footprint ""
		(layer "F.Cu")
		(at 12.04595 -316.361826 -90)
		(property "Reference" "PL17"
			(at -0.509016 -1.910334 90)
			(unlocked yes)
			(layer "F.SilkS")
			(effects
				(font
					(size 0.7874 0.5842)
					(thickness 0.1524)
				)
			)
		)
		(property "Value" ""
			(at 0 0 270)
			(layer "F.Fab")
			(effects
				(font
					(size 1.27 1.27)
				)
			)
		)
		(duplicate_pad_numbers_are_jumpers no)
		(fp_line
			(start -1.27 0.5842)
			(end -1.27 -0.5842)
			(stroke
				(width 0.1524)
				(type default)
			)
			(layer "F.SilkS")
		)
		(fp_line
			(start 1.27 0.5842)
			(end -1.27 0.5842)
			(stroke
				(width 0.1524)
				(type default)
			)
			(layer "F.SilkS")
		)
		(fp_line
			(start 1.27 0.5842)
			(end 1.27 -0.5842)
			(stroke
				(width 0.1524)
				(type default)
			)
			(layer "F.SilkS")
		)
		(fp_line
			(start -1.27 -0.5588)
			(end -1.27 -0.5842)
			(stroke
				(width 0.1524)
				(type default)
			)
			(layer "F.SilkS")
		)
		(fp_line
			(start -1.27 -0.5842)
			(end 1.27 -0.5842)
			(stroke
				(width 0.1524)
				(type default)
			)
			(layer "F.SilkS")
		)
		(fp_line
			(start -0.9144 0.508)
			(end -0.9144 0.406654)
			(stroke
				(width 0.1)
				(type default)
			)
			(layer "F.Fab")
		)
		(fp_line
			(start 0.9144 0.508)
			(end -0.9144 0.508)
			(stroke
				(width 0.1)
				(type default)
			)
			(layer "F.Fab")
		)
		(fp_line
			(start -1.194308 0.406654)
			(end -1.194308 -0.406654)
			(stroke
				(width 0.1)
				(type default)
			)
			(layer "F.Fab")
		)
		(fp_line
			(start -0.9144 0.406654)
			(end -1.194308 0.406654)
			(stroke
				(width 0.1)
				(type default)
			)
			(layer "F.Fab")
		)
		(fp_line
			(start 0.9144 0.4064)
			(end 0.9144 0.508)
			(stroke
				(width 0.1)
				(type default)
			)
			(layer "F.Fab")
		)
		(fp_line
			(start 1.1938 0.4064)
			(end 0.9144 0.4064)
			(stroke
				(width 0.1)
				(type default)
			)
			(layer "F.Fab")
		)
		(fp_line
			(start -1.194308 -0.406654)
			(end -0.9144 -0.406654)
			(stroke
				(width 0.1)
				(type default)
			)
			(layer "F.Fab")
		)
		(fp_line
			(start -0.9144 -0.406654)
			(end -0.9144 -0.508)
			(stroke
				(width 0.1)
				(type default)
			)
			(layer "F.Fab")
		)
		(fp_line
			(start 0.9144 -0.406654)
			(end 1.1938 -0.406654)
			(stroke
				(width 0.1)
				(type default)
			)
			(layer "F.Fab")
		)
		(fp_line
			(start 1.1938 -0.406654)
			(end 1.1938 0.4064)
			(stroke
				(width 0.1)
				(type default)
			)
			(layer "F.Fab")
		)
		(fp_line
			(start -0.9144 -0.508)
			(end 0.9144 -0.508)
			(stroke
				(width 0.1)
				(type default)
			)
			(layer "F.Fab")
		)
		(fp_line
			(start 0.9144 -0.508)
			(end 0.9144 -0.406654)
			(stroke
				(width 0.1)
				(type default)
			)
			(layer "F.Fab")
		)
		(pad "1" smd rect
			(at -0.7366 0 180)
			(size 0.7112 0.8128)
			(layers "F.Cu" "F.Mask" "F.Paste")
			(net "P12V_AUX")
		)
		(pad "2" smd rect
			(at 0.7366 0 180)
			(size 0.7112 0.8128)
			(layers "F.Cu" "F.Mask" "F.Paste")
			(net "SW_P12V_P1V25_PEX0_FLT")
		)
	)
	(footprint ""
		(layer "F.Cu")
		(at 1.650746 -34.890456 -90)
		(property "Reference" "C2711"
			(at 0 0 270)
			(layer "F.SilkS")
			(hide yes)
			(effects
				(font
					(size 1.27 1.27)
				)
			)
		)
		(property "Value" ""
			(at 0 0 270)
			(layer "F.Fab")
			(effects
				(font
					(size 1.27 1.27)
				)
			)
		)
		(duplicate_pad_numbers_are_jumpers no)
		(fp_line
			(start -0.7874 0.4064)
			(end -0.7874 -0.4064)
			(stroke
				(width 0.1524)
				(type default)
			)
			(layer "F.SilkS")
		)
		(fp_line
			(start 0.7874 0.4064)
			(end -0.7874 0.4064)
			(stroke
				(width 0.1524)
				(type default)
			)
			(layer "F.SilkS")
		)
		(fp_line
			(start -0.7874 -0.4064)
			(end 0.7874 -0.4064)
			(stroke
				(width 0.1524)
				(type default)
			)
			(layer "F.SilkS")
		)
		(fp_line
			(start 0.7874 -0.4064)
			(end 0.7874 0.4064)
			(stroke
				(width 0.1524)
				(type default)
			)
			(layer "F.SilkS")
		)
		(fp_line
			(start -0.67945 0.3048)
			(end -0.67945 -0.305054)
			(stroke
				(width 0.1)
				(type default)
			)
			(layer "F.Fab")
		)
		(fp_line
			(start -0.12065 0.3048)
			(end -0.67945 0.3048)
			(stroke
				(width 0.1)
				(type default)
			)
			(layer "F.Fab")
		)
		(fp_line
			(start 0.120396 0.3048)
			(end 0.120396 0.2794)
			(stroke
				(width 0.1)
				(type default)
			)
			(layer "F.Fab")
		)
		(fp_line
			(start 0.67945 0.3048)
			(end 0.120396 0.3048)
			(stroke
				(width 0.1)
				(type default)
			)
			(layer "F.Fab")
		)
		(fp_line
			(start -0.12065 0.2794)
			(end -0.12065 0.3048)
			(stroke
				(width 0.1)
				(type default)
			)
			(layer "F.Fab")
		)
		(fp_line
			(start 0.120396 0.2794)
			(end -0.12065 0.2794)
			(stroke
				(width 0.1)
				(type default)
			)
			(layer "F.Fab")
		)
		(fp_line
			(start -0.12065 -0.2794)
			(end 0.12065 -0.2794)
			(stroke
				(width 0.1)
				(type default)
			)
			(layer "F.Fab")
		)
		(fp_line
			(start 0.12065 -0.2794)
			(end 0.12065 -0.3048)
			(stroke
				(width 0.1)
				(type default)
			)
			(layer "F.Fab")
		)
		(fp_line
			(start 0.12065 -0.3048)
			(end 0.67945 -0.3048)
			(stroke
				(width 0.1)
				(type default)
			)
			(layer "F.Fab")
		)
		(fp_line
			(start 0.67945 -0.3048)
			(end 0.67945 0.3048)
			(stroke
				(width 0.1)
				(type default)
			)
			(layer "F.Fab")
		)
		(fp_line
			(start -0.67945 -0.305054)
			(end -0.12065 -0.305054)
			(stroke
				(width 0.1)
				(type default)
			)
			(layer "F.Fab")
		)
		(fp_line
			(start -0.12065 -0.305054)
			(end -0.12065 -0.2794)
			(stroke
				(width 0.1)
				(type default)
			)
			(layer "F.Fab")
		)
		(pad "1" smd circle
			(at -0.40005 0 270)
			(size 0 0)
			(layers "F.Cu" "F.Mask" "F.Paste")
			(net "GND")
		)
		(pad "2" smd circle
			(at 0.40005 0 270)
			(size 0 0)
			(layers "F.Cu" "F.Mask" "F.Paste")
			(net "P3V3_AUX")
		)
	)
	(footprint ""
		(layer "F.Cu")
		(at 207.270858 -220.79077 90)
		(property "Reference" "R5473"
			(at 0 0 90)
			(layer "F.SilkS")
			(hide yes)
			(effects
				(font
					(size 1.27 1.27)
				)
			)
		)
		(property "Value" ""
			(at 0 0 90)
			(layer "F.Fab")
			(effects
				(font
					(size 1.27 1.27)
				)
			)
		)
		(duplicate_pad_numbers_are_jumpers no)
		(fp_line
			(start 0.7874 -0.4064)
			(end 0.7874 0.4064)
			(stroke
				(width 0.1524)
				(type default)
			)
			(layer "F.SilkS")
		)
		(fp_line
			(start -0.7874 -0.4064)
			(end 0.7874 -0.4064)
			(stroke
				(width 0.1524)
				(type default)
			)
			(layer "F.SilkS")
		)
		(fp_line
			(start 0.7874 0.4064)
			(end -0.7874 0.4064)
			(stroke
				(width 0.1524)
				(type default)
			)
			(layer "F.SilkS")
		)
		(fp_line
			(start -0.7874 0.4064)
			(end -0.7874 -0.4064)
			(stroke
				(width 0.1524)
				(type default)
			)
			(layer "F.SilkS")
		)
		(fp_line
			(start -0.12065 -0.305054)
			(end -0.12065 -0.2794)
			(stroke
				(width 0.1)
				(type default)
			)
			(layer "F.Fab")
		)
		(fp_line
			(start -0.67945 -0.305054)
			(end -0.12065 -0.305054)
			(stroke
				(width 0.1)
				(type default)
			)
			(layer "F.Fab")
		)
		(fp_line
			(start 0.67945 -0.3048)
			(end 0.67945 0.3048)
			(stroke
				(width 0.1)
				(type default)
			)
			(layer "F.Fab")
		)
		(fp_line
			(start 0.12065 -0.3048)
			(end 0.67945 -0.3048)
			(stroke
				(width 0.1)
				(type default)
			)
			(layer "F.Fab")
		)
		(fp_line
			(start 0.12065 -0.2794)
			(end 0.12065 -0.3048)
			(stroke
				(width 0.1)
				(type default)
			)
			(layer "F.Fab")
		)
		(fp_line
			(start -0.12065 -0.2794)
			(end 0.12065 -0.2794)
			(stroke
				(width 0.1)
				(type default)
			)
			(layer "F.Fab")
		)
		(fp_line
			(start 0.120396 0.2794)
			(end -0.12065 0.2794)
			(stroke
				(width 0.1)
				(type default)
			)
			(layer "F.Fab")
		)
		(fp_line
			(start -0.12065 0.2794)
			(end -0.12065 0.3048)
			(stroke
				(width 0.1)
				(type default)
			)
			(layer "F.Fab")
		)
		(fp_line
			(start 0.67945 0.3048)
			(end 0.120396 0.3048)
			(stroke
				(width 0.1)
				(type default)
			)
			(layer "F.Fab")
		)
		(fp_line
			(start 0.120396 0.3048)
			(end 0.120396 0.2794)
			(stroke
				(width 0.1)
				(type default)
			)
			(layer "F.Fab")
		)
		(fp_line
			(start -0.12065 0.3048)
			(end -0.67945 0.3048)
			(stroke
				(width 0.1)
				(type default)
			)
			(layer "F.Fab")
		)
		(fp_line
			(start -0.67945 0.3048)
			(end -0.67945 -0.305054)
			(stroke
				(width 0.1)
				(type default)
			)
			(layer "F.Fab")
		)
		(pad "1" smd circle
			(at -0.40005 0 90)
			(size 0 0)
			(layers "F.Cu" "F.Mask" "F.Paste")
			(net "UART_MB_BIC_RX_BUF_R")
		)
		(pad "2" smd circle
			(at 0.40005 0 90)
			(size 0 0)
			(layers "F.Cu" "F.Mask" "F.Paste")
			(net "UART_MB_BIC_RX_BUF")
		)
	)
)
